FILE_TYPE = MULTI_PHYS_TABLE;

PART 'PCA9617ADP'

{========================================================================================}
:VALUE        | PART_TYPE | MATERIAL | PART_NUMBER    = STANDARD    | LIFECYCLE          | PART_NUMBER   | JEDEC_TYPE   | DESCRIPTION                      | MANUFTR | MANUF_PN     | RD_CMPLS_LVL | CMPLS_LVL | FROM_PJ    | CLASS | DIP_SMD | DATA               | EE_CHECK_LIST | FP_ECN | PSL | CREATOR | STATUS | CREATEDAY  ;
{========================================================================================}
 'PCA9617ADP' | 'SMLF'    | 'IC'     | 'AL009617K02'(!) = ''               | ''               | 'AL009617K02' |'TSSOP8_3XB'| 'IC OTHER(8P) PCA9617ADP(TSSOP)' | 'NXP'   | 'PCA9617ADP' | 'EP(V1)'     | ''        | 'S1U-OWEN' | 'IC'  | ''      | 'NXP_PCA9617A.pdf' | ''            | ''     | ''  | ''      | ''     | '20140410'
 'PCA9617ADP' | 'SMLF'    | 'EMPTY'  | 'AL009617K02'(!) = ''               | ''               | 'AL009617K02' |'TSSOP8_3XB'| 'IC OTHER(8P) PCA9617ADP(TSSOP)' | 'NXP'   | 'PCA9617ADP' | 'EP(V1)'     | ''        | 'S1U-OWEN' | 'IC'  | ''      | 'NXP_PCA9617A.pdf' | ''            | ''     | ''  | ''      | ''     | '20140410'

END_PART

END.

